(kicad_pcb
	(version 20241229)
	(generator "pcbnew")
	(generator_version "9.0")
	(general
		(thickness 1.552)
		(legacy_teardrops no)
	)
	(paper "A4")
	(title_block
		(date "2023-07-25")
		(rev "1.1.4")
		(comment 9 "footprints 238-239 of 379")
	)
	(layers
		(0 "F.Cu" signal)
		(4 "In1.Cu" signal)
		(6 "In2.Cu" signal)
		(8 "In3.Cu" signal)
		(10 "In4.Cu" signal)
		(12 "In5.Cu" signal)
		(14 "In6.Cu" signal)
		(2 "B.Cu" signal)
		(9 "F.Adhes" user "F.Adhesive")
		(11 "B.Adhes" user "B.Adhesive")
		(13 "F.Paste" user)
		(15 "B.Paste" user)
		(5 "F.SilkS" user "F.Silkscreen")
		(7 "B.SilkS" user "B.Silkscreen")
		(1 "F.Mask" user)
		(3 "B.Mask" user)
		(17 "Dwgs.User" user "User.Drawings")
		(19 "Cmts.User" user "User.Comments")
		(21 "Eco1.User" user "User.Eco1")
		(23 "Eco2.User" user "User.Eco2")
		(25 "Edge.Cuts" user)
		(27 "Margin" user)
		(31 "F.CrtYd" user "F.Courtyard")
		(29 "B.CrtYd" user "B.Courtyard")
		(35 "F.Fab" user)
		(33 "B.Fab" user)
	)
	(footprint "antmicro-footprints:QFN-16-1EP_4x4mm_P0.65mm"
		(layer "F.Cu")
		(at 89 105.85 180)
		(property "Reference" "U16"
			(at -3.13 2.61 0)
			(layer "F.SilkS")
			(effects
				(font
					(size 0.65 0.65)
					(thickness 0.15)
				)
				(justify right bottom)
			)
		)
		(property "Value" "GS2988"
			(at 0 3.3 0)
			(layer "F.Fab")
			(hide yes)
			(effects
				(font
					(size 0.7 0.7)
					(thickness 0.15)
				)
				(justify right bottom)
			)
		)
		(property "Datasheet" "https://semtech.my.salesforce.com/sfc/p/#E0000000JelG/a/44000000MDIY/URmNPYk6YrvngFjCh2n.ZRVsjLb90QOH1YLezdH9vhM"
			(at 0 0 180)
			(layer "F.Fab")
			(hide yes)
			(effects
				(font
					(size 1.27 1.27)
					(thickness 0.15)
				)
			)
		)
		(property "Description" "SDI driver"
			(at 0 0 180)
			(layer "F.Fab")
			(hide yes)
			(effects
				(font
					(size 1.27 1.27)
					(thickness 0.15)
				)
			)
		)
		(property "Author" "Antmicro"
			(at 178 211.7 0)
			(layer "F.Fab")
			(hide yes)
			(effects
				(font
					(size 1 1)
					(thickness 0.15)
				)
			)
		)
		(property "License" "Apache-2.0"
			(at 178 211.7 0)
			(layer "F.Fab")
			(hide yes)
			(effects
				(font
					(size 1 1)
					(thickness 0.15)
				)
			)
		)
		(property "MPN" "GS2988-INE3"
			(at 178 211.7 0)
			(layer "F.Fab")
			(hide yes)
			(effects
				(font
					(size 1 1)
					(thickness 0.15)
				)
			)
		)
		(property "Manufacturer" "Semtech"
			(at 178 211.7 0)
			(layer "F.Fab")
			(hide yes)
			(effects
				(font
					(size 1 1)
					(thickness 0.15)
				)
			)
		)
		(sheetname "/SDI/")
		(sheetfile "sdi.kicad_sch")
		(attr smd)
		(fp_line
			(start 2.1 2.1)
			(end 2.1 1.398)
			(stroke
				(width 0.15)
				(type solid)
			)
			(layer "F.SilkS")
		)
		(fp_line
			(start 2.1 -2.101)
			(end 2.1 -1.401)
			(stroke
				(width 0.15)
				(type solid)
			)
			(layer "F.SilkS")
		)
		(fp_line
			(start 1.499 2.1)
			(end 2.1 2.1)
			(stroke
				(width 0.15)
				(type solid)
			)
			(layer "F.SilkS")
		)
		(fp_line
			(start 1.499 -2.101)
			(end 2.1 -2.101)
			(stroke
				(width 0.15)
				(type solid)
			)
			(layer "F.SilkS")
		)
		(fp_line
			(start -1.4 -2.1)
			(end -2.1 -2.1)
			(stroke
				(width 0.15)
				(type solid)
			)
			(layer "F.SilkS")
		)
		(fp_line
			(start -2.1 -2.1)
			(end -2.101 -1.4)
			(stroke
				(width 0.15)
				(type solid)
			)
			(layer "F.SilkS")
		)
		(fp_line
			(start -2.101 2.1)
			(end -1.5 2.1)
			(stroke
				(width 0.15)
				(type solid)
			)
			(layer "F.SilkS")
		)
		(fp_line
			(start -2.101 1.398)
			(end -2.101 2.1)
			(stroke
				(width 0.15)
				(type solid)
			)
			(layer "F.SilkS")
		)
		(fp_circle
			(center -2.35 -1.4)
			(end -2.3 -1.4)
			(stroke
				(width 0.15)
				(type solid)
			)
			(fill yes)
			(layer "F.SilkS")
		)
		(fp_rect
			(start -2.35 -2.35)
			(end 2.35 2.35)
			(stroke
				(width 0.05)
				(type solid)
			)
			(fill no)
			(layer "F.CrtYd")
		)
		(fp_line
			(start -1.5 -2)
			(end -2 -1.5)
			(stroke
				(width 0.15)
				(type solid)
			)
			(layer "F.Fab")
		)
		(fp_rect
			(start 2 2)
			(end -2 -2)
			(stroke
				(width 0.15)
				(type solid)
			)
			(fill no)
			(layer "F.Fab")
		)
		(fp_text user "License: Apache-2.0"
			(at -2.35 7.999 180)
			(layer "F.Fab")
			(effects
				(font
					(size 0.7 0.7)
					(thickness 0.15)
				)
				(justify left bottom)
			)
		)
		(fp_text user "Author: Antmicro"
			(at -2.35 6.799 180)
			(layer "F.Fab")
			(effects
				(font
					(size 0.7 0.7)
					(thickness 0.15)
				)
				(justify left bottom)
			)
		)
		(fp_text user "${REFERENCE}"
			(at -2.35 5.599 180)
			(layer "F.Fab")
			(effects
				(font
					(size 0.7 0.7)
					(thickness 0.15)
				)
				(justify left bottom)
			)
		)
		(pad "1" smd rect
			(at -1.9 -0.975 180)
			(size 0.8 0.4)
			(layers "F.Cu" "F.Mask" "F.Paste")
			(net 47 "/SDI/SDO_P")
			(pinfunction "DDI+")
			(pintype "input")
		)
		(pad "2" smd rect
			(at -1.9 -0.325 180)
			(size 0.8 0.4)
			(layers "F.Cu" "F.Mask" "F.Paste")
			(net 48 "/SDI/SDO_N")
			(pinfunction "DDI-")
			(pintype "input")
		)
		(pad "3" smd rect
			(at -1.9 0.325 180)
			(size 0.8 0.4)
			(layers "F.Cu" "F.Mask" "F.Paste")
			(net 1 "GND")
			(pinfunction "V_{EE}")
			(pintype "power_in")
		)
		(pad "4" smd rect
			(at -1.9 0.975 180)
			(size 0.8 0.4)
			(layers "F.Cu" "F.Mask" "F.Paste")
			(net 289 "Net-(U16-RSET)")
			(pinfunction "RSET")
			(pintype "passive")
		)
		(pad "5" smd rect
			(at -0.975 1.9 180)
			(size 0.4 0.8)
			(layers "F.Cu" "F.Mask" "F.Paste")
			(net 391 "unconnected-(U16-NC-Pad5)")
			(pinfunction "NC")
			(pintype "no_connect")
		)
		(pad "6" smd rect
			(at -0.325 1.9 180)
			(size 0.4 0.8)
			(layers "F.Cu" "F.Mask" "F.Paste")
			(net 184 "/SDI/~{SDO_DISABLE}")
			(pinfunction "~{DISABLE}")
			(pintype "input")
		)
		(pad "7" smd rect
			(at 0.325 1.9 180)
			(size 0.4 0.8)
			(layers "F.Cu" "F.Mask" "F.Paste")
			(net 392 "unconnected-(U16-NC-Pad7)")
			(pinfunction "NC")
			(pintype "no_connect")
		)
		(pad "8" smd rect
			(at 0.975 1.9 180)
			(size 0.4 0.8)
			(layers "F.Cu" "F.Mask" "F.Paste")
			(net 393 "unconnected-(U16-NC-Pad8)")
			(pinfunction "NC")
			(pintype "no_connect")
		)
		(pad "9" smd rect
			(at 1.9 0.975 180)
			(size 0.8 0.4)
			(layers "F.Cu" "F.Mask" "F.Paste")
			(net 2 "+3V3")
			(pinfunction "V_{CC}")
			(pintype "power_in")
		)
		(pad "10" smd rect
			(at 1.9 0.325 180)
			(size 0.8 0.4)
			(layers "F.Cu" "F.Mask" "F.Paste")
			(net 1 "GND")
			(pinfunction "SD/~{HD}")
			(pintype "input")
		)
		(pad "11" smd rect
			(at 1.9 -0.325 180)
			(size 0.8 0.4)
			(layers "F.Cu" "F.Mask" "F.Paste")
			(net 254 "/SDI/SDI_OUT_N")
			(pinfunction "SDO-")
			(pintype "output")
		)
		(pad "12" smd rect
			(at 1.9 -0.975 180)
			(size 0.8 0.4)
			(layers "F.Cu" "F.Mask" "F.Paste")
			(net 249 "/SDI/SDI_OUT_P")
			(pinfunction "SDO+")
			(pintype "output")
		)
		(pad "13" smd rect
			(at 0.975 -1.9 180)
			(size 0.4 0.8)
			(layers "F.Cu" "F.Mask" "F.Paste")
			(net 394 "unconnected-(U16-NC-Pad13)")
			(pinfunction "NC")
			(pintype "no_connect")
		)
		(pad "14" smd rect
			(at 0.325 -1.9 180)
			(size 0.4 0.8)
			(layers "F.Cu" "F.Mask" "F.Paste")
			(net 378 "Net-(U16-~{OSP})")
			(pinfunction "~{OSP}")
			(pintype "output")
		)
		(pad "15" smd rect
			(at -0.325 -1.9 180)
			(size 0.4 0.8)
			(layers "F.Cu" "F.Mask" "F.Paste")
			(net 395 "unconnected-(U16-NC-Pad15)")
			(pinfunction "NC")
			(pintype "no_connect")
		)
		(pad "16" smd rect
			(at -0.975 -1.9 180)
			(size 0.4 0.8)
			(layers "F.Cu" "F.Mask" "F.Paste")
			(net 285 "Net-(U16-~{EQ_EN})")
			(pinfunction "~{EQ_EN}")
			(pintype "input")
		)
		(pad "17" smd rect
			(at 0 0 180)
			(size 2.3 2.3)
			(layers "F.Cu" "F.Mask" "F.Paste")
			(net 1 "GND")
			(pinfunction "EP")
			(pintype "passive")
		)
	)
	(footprint "antmicro-footprints:SOT-23-6"
		(layer "F.Cu")
		(at 163.39 80)
		(property "Reference" "U19"
			(at -3.76 -1.26 0)
			(layer "F.SilkS")
			(effects
				(font
					(size 0.65 0.65)
					(thickness 0.15)
				)
				(justify left bottom)
			)
		)
		(property "Value" "DIO7553ST6"
			(at -1.75 2.75 0)
			(layer "F.Fab")
			(hide yes)
			(effects
				(font
					(size 0.7 0.7)
					(thickness 0.15)
				)
				(justify left bottom)
			)
		)
		(property "Datasheet" "https://www.mouser.com/datasheet/2/802/7e5c577022fb784effcb3cdb25b437c0-1815562.pdf"
			(at 0 0 0)
			(layer "F.Fab")
			(hide yes)
			(effects
				(font
					(size 1.27 1.27)
					(thickness 0.15)
				)
			)
		)
		(property "Description" "Power switch"
			(at 0 0 0)
			(layer "F.Fab")
			(hide yes)
			(effects
				(font
					(size 1.27 1.27)
					(thickness 0.15)
				)
			)
		)
		(property "Author" "Antmicro"
			(at 0 0 0)
			(layer "F.Fab")
			(hide yes)
			(effects
				(font
					(size 1 1)
					(thickness 0.15)
				)
			)
		)
		(property "License" "Apache-2.0"
			(at 0 0 0)
			(layer "F.Fab")
			(hide yes)
			(effects
				(font
					(size 1 1)
					(thickness 0.15)
				)
			)
		)
		(property "MPN" "DIO7553ST6"
			(at 0 0 0)
			(layer "F.Fab")
			(hide yes)
			(effects
				(font
					(size 1 1)
					(thickness 0.15)
				)
			)
		)
		(property "Manufacturer" "DIOO Microcircuits"
			(at 0 0 0)
			(layer "F.Fab")
			(hide yes)
			(effects
				(font
					(size 1 1)
					(thickness 0.15)
				)
			)
		)
		(sheetname "/Peripherals/")
		(sheetfile "peripherals.kicad_sch")
		(attr smd)
		(fp_line
			(start -1.45 -0.757)
			(end -1.45 -0.457)
			(stroke
				(width 0.12)
				(type solid)
			)
			(layer "F.SilkS")
		)
		(fp_line
			(start -1.45 0.643)
			(end -1.45 0.343)
			(stroke
				(width 0.12)
				(type solid)
			)
			(layer "F.SilkS")
		)
		(fp_line
			(start -1.3 -0.757)
			(end -1.45 -0.757)
			(stroke
				(width 0.12)
				(type solid)
			)
			(layer "F.SilkS")
		)
		(fp_line
			(start 1.3 -0.757)
			(end 1.45 -0.757)
			(stroke
				(width 0.12)
				(type solid)
			)
			(layer "F.SilkS")
		)
		(fp_line
			(start 1.3 0.643)
			(end 1.45 0.643)
			(stroke
				(width 0.12)
				(type solid)
			)
			(layer "F.SilkS")
		)
		(fp_line
			(start 1.45 -0.757)
			(end 1.45 -0.457)
			(stroke
				(width 0.12)
				(type solid)
			)
			(layer "F.SilkS")
		)
		(fp_line
			(start 1.45 0.643)
			(end 1.45 0.343)
			(stroke
				(width 0.12)
				(type solid)
			)
			(layer "F.SilkS")
		)
		(fp_rect
			(start -1.55 -1.85)
			(end 1.55 1.75)
			(stroke
				(width 0.05)
				(type solid)
			)
			(fill no)
			(layer "F.CrtYd")
		)
		(fp_line
			(start -1.5 -0.757)
			(end 1.5 -0.757)
			(stroke
				(width 0.1)
				(type solid)
			)
			(layer "F.Fab")
		)
		(fp_line
			(start -1.5 0.643)
			(end -1.5 -0.757)
			(stroke
				(width 0.1)
				(type solid)
			)
			(layer "F.Fab")
		)
		(fp_line
			(start 1.5 -0.757)
			(end 1.5 0.643)
			(stroke
				(width 0.1)
				(type solid)
			)
			(layer "F.Fab")
		)
		(fp_line
			(start 1.5 0.643)
			(end -1.5 0.643)
			(stroke
				(width 0.1)
				(type solid)
			)
			(layer "F.Fab")
		)
		(fp_text user "."
			(at -1.4 1.2 180)
			(layer "F.SilkS")
			(effects
				(font
					(size 1 1)
					(thickness 0.15)
				)
			)
		)
		(fp_text user "${REFERENCE}"
			(at -1.75 4 0)
			(layer "F.Fab")
			(effects
				(font
					(size 0.7 0.7)
					(thickness 0.15)
				)
				(justify left bottom)
			)
		)
		(fp_text user "License: Apache-2.0"
			(at -1.75 6.5 0)
			(layer "F.Fab")
			(effects
				(font
					(size 0.7 0.7)
					(thickness 0.15)
				)
				(justify left bottom)
			)
		)
		(fp_text user "Author: Antmicro"
			(at -1.829 5.25 0)
			(layer "F.Fab")
			(effects
				(font
					(size 0.7 0.7)
					(thickness 0.15)
				)
				(justify left bottom)
			)
		)
		(pad "1" smd roundrect
			(at -0.954 1.1)
			(size 0.55 1)
			(layers "F.Cu" "F.Mask" "F.Paste")
			(roundrect_rratio 0.15)
			(net 2 "+3V3")
			(pinfunction "IN")
			(pintype "power_in")
		)
		(pad "2" smd roundrect
			(at -0.003 1.1)
			(size 0.55 1)
			(layers "F.Cu" "F.Mask" "F.Paste")
			(roundrect_rratio 0.15)
			(net 1 "GND")
			(pinfunction "GND")
			(pintype "power_in")
		)
		(pad "3" smd roundrect
			(at 0.947 1.1)
			(size 0.55 1)
			(layers "F.Cu" "F.Mask" "F.Paste")
			(roundrect_rratio 0.15)
			(net 315 "/Peripherals/QWIIC_PEN")
			(pinfunction "EN")
			(pintype "input")
		)
		(pad "4" smd roundrect
			(at 0.947 -1.214)
			(size 0.55 1)
			(layers "F.Cu" "F.Mask" "F.Paste")
			(roundrect_rratio 0.15)
			(net 314 "/Peripherals/QW_FLT")
			(pinfunction "~{FAULT}")
			(pintype "output")
		)
		(pad "5" smd roundrect
			(at -0.003 -1.214)
			(size 0.55 1)
			(layers "F.Cu" "F.Mask" "F.Paste")
			(roundrect_rratio 0.15)
			(net 356 "Net-(U19-ILIM)")
			(pinfunction "ILIM")
			(pintype "passive")
		)
		(pad "6" smd roundrect
			(at -0.954 -1.214)
			(size 0.55 1)
			(layers "F.Cu" "F.Mask" "F.Paste")
			(roundrect_rratio 0.15)
			(net 310 "/Peripherals/QWIIC_3V3")
			(pinfunction "OUT")
			(pintype "power_out")
		)
	)
)
